# T6G (Grand Teton) — schematic netlist excerpt (pin names and nets, part order shuffled) for the footprints in the layout excerpt that follows; sources: Cadence DE-HDL packaged netlist, KiCad conversion of 04192023_DAF0TMB3IC0_F0TG_MB_C_brd_V02_OCP.brd

J84  PICOPROBE_BXA  DELTA-L 4.0 EMPTY  pkg TRIANG_LAUNCH_3PXB  page 229
  \1_p\  = DELTA_L_85_10INCH_IN2_DN
  \2_n\  = DELTA_L_85_10INCH_IN2_DP
  \3_g\  = DELTA_L_GND_1

(kicad_pcb
	(version 20260206)
	(generator "pcbnew")
	(generator_version "10.0")
	(general
		(thickness 1.6)
		(legacy_teardrops no)
	)
	(paper "A4")
	(title_block
		(title "04192023_DAF0TMB3IC0_F0TG_MB_C_brd_V02_OCP.brd")
		(comment 1 "Grand Teton / footprints 3076-3076 of 8354")
	)
	(layers
		(0 "F.Cu" signal "TOP")
		(4 "In1.Cu" signal "GND")
		(6 "In2.Cu" signal "IN1")
		(8 "In3.Cu" signal "GND1")
		(10 "In4.Cu" signal "IN2")
		(12 "In5.Cu" signal "GND2")
		(14 "In6.Cu" signal "IN3")
		(16 "In7.Cu" signal "GND3")
		(18 "In8.Cu" signal "VCC")
		(20 "In9.Cu" signal "VCC1")
		(22 "In10.Cu" signal "GND4")
		(24 "In11.Cu" signal "IN4")
		(26 "In12.Cu" signal "GND5")
		(28 "In13.Cu" signal "IN5")
		(30 "In14.Cu" signal "GND6")
		(32 "In15.Cu" signal "IN6")
		(34 "In16.Cu" signal "GND7")
		(2 "B.Cu" signal "BOTTOM")
		(9 "F.Adhes" user "F.Adhesive")
		(11 "B.Adhes" user "B.Adhesive")
		(13 "F.Paste" user "Package Geometry/Pastemask Top")
		(15 "B.Paste" user "Package Geometry/Pastemask Bottom")
		(5 "F.SilkS" user "Ref Des/Silkscreen Top")
		(7 "B.SilkS" user "Ref Des/Silkscreen Bottom")
		(1 "F.Mask" user "Board Geometry/Soldermask Top")
		(3 "B.Mask" user "Board Geometry/Soldermask Bottom")
		(17 "Dwgs.User" user "User.Drawings")
		(19 "Cmts.User" user "User.Comments")
		(21 "Eco1.User" user "User.Eco1")
		(23 "Eco2.User" user "User.Eco2")
		(25 "Edge.Cuts" user "Board Geometry/Outline")
		(27 "Margin" user)
		(31 "F.CrtYd" user "Package Geometry/Place Bound Top")
		(29 "B.CrtYd" user "Package Geometry/Place Bound Bottom")
		(35 "F.Fab" user "Ref Des/Assembly Top")
		(33 "B.Fab" user "Ref Des/Assembly Bottom")
	)
	(footprint ""
		(layer "F.Cu")
		(at 300.538388 -5.077206 180)
		(property "Reference" "J84"
			(at -4.342384 -1.077976 90)
			(unlocked yes)
			(layer "F.SilkS")
			(effects
				(font
					(size 0.7874 0.5842)
					(thickness 0.1524)
				)
				(justify left)
			)
		)
		(property "Value" ""
			(at 0 0 180)
			(layer "F.Fab")
			(effects
				(font
					(size 1.27 1.27)
				)
			)
		)
		(duplicate_pad_numbers_are_jumpers no)
		(fp_line
			(start 1.2192 2.06756)
			(end -1.2192 2.06756)
			(stroke
				(width 0.1524)
				(type default)
			)
			(layer "F.SilkS")
		)
		(fp_line
			(start 1.2192 -2.06756)
			(end 1.2192 2.06756)
			(stroke
				(width 0.1524)
				(type default)
			)
			(layer "F.SilkS")
		)
		(fp_line
			(start -1.2192 2.06756)
			(end -1.2192 -2.06756)
			(stroke
				(width 0.1524)
				(type default)
			)
			(layer "F.SilkS")
		)
		(fp_line
			(start -1.2192 -2.06756)
			(end 1.2192 -2.06756)
			(stroke
				(width 0.1524)
				(type default)
			)
			(layer "F.SilkS")
		)
		(pad "" np_thru_hole circle
			(at -2.8829 -1.27 90)
			(size 1.0414 1.0414)
			(drill 1.0414)
			(layers "*.Cu" "*.Mask")
			(clearance 0.381)
			(thermal_gap 0.381)
		)
		(pad "" np_thru_hole circle
			(at -2.8829 1.27 90)
			(size 1.0414 1.0414)
			(drill 1.0414)
			(layers "*.Cu" "*.Mask")
			(clearance 0.381)
			(thermal_gap 0.381)
		)
		(pad "" np_thru_hole circle
			(at 3.4671 -1.27 90)
			(size 1.0414 1.0414)
			(drill 1.0414)
			(layers "*.Cu" "*.Mask")
			(clearance 0.381)
			(thermal_gap 0.381)
		)
		(pad "" np_thru_hole circle
			(at 3.4671 1.27 90)
			(size 1.0414 1.0414)
			(drill 1.0414)
			(layers "*.Cu" "*.Mask")
			(clearance 0.381)
			(thermal_gap 0.381)
		)
		(pad "1" smd rect
			(at 0.8255 -0.249936 90)
			(size 0.3048 0.508)
			(layers "F.Cu" "F.Mask" "F.Paste")
			(net "DELTA_L_85_10INCH_IN2_DN")
		)
		(pad "2" smd rect
			(at 0.8255 0.249936 90)
			(size 0.3048 0.508)
			(layers "F.Cu" "F.Mask" "F.Paste")
			(net "DELTA_L_85_10INCH_IN2_DP")
		)
		(pad "3" smd circle
			(at 0 0 180)
			(size 0 0)
			(layers "F.Cu" "F.Mask" "F.Paste")
			(net "DELTA_L_GND_1")
		)
		(zone
			(layer "F.Cu")
			(hatch none 0.5)
			(connect_pads
				(clearance 0)
			)
			(min_thickness 0.25)
			(keepout
				(tracks not_allowed)
				(vias allowed)
				(pads allowed)
				(copperpour not_allowed)
				(footprints allowed)
			)
			(placement
				(enabled no)
				(sheetname "")
			)
			(fill
				(thermal_gap 0.5)
				(thermal_bridge_width 0.5)
				(island_removal_mode 0)
			)
			(polygon
				(pts
					(xy 299.420788 -4.528566) (xy 299.420788 -4.62407) (xy 300.017688 -4.62407) (xy 300.017688 -5.03047)
					(xy 299.420788 -5.03047) (xy 299.420788 -5.123942) (xy 300.017688 -5.123942) (xy 300.017688 -5.530342)
					(xy 299.420788 -5.530342) (xy 299.420788 -5.625846) (xy 300.119288 -5.625846) (xy 300.119288 -4.528566)
				)
			)
		)
		(zone
			(layers "F.Cu" "B.Cu" "In1.Cu" "In2.Cu" "In3.Cu" "In4.Cu" "In5.Cu" "In6.Cu"
				"In7.Cu" "In8.Cu" "In9.Cu" "In10.Cu" "In11.Cu" "In12.Cu" "In13.Cu" "In14.Cu"
				"In15.Cu" "In16.Cu"
			)
			(hatch none 0.5)
			(connect_pads
				(clearance 0)
			)
			(min_thickness 0.25)
			(keepout
				(tracks not_allowed)
				(vias allowed)
				(pads allowed)
				(copperpour not_allowed)
				(footprints allowed)
			)
			(placement
				(enabled no)
				(sheetname "")
			)
			(fill
				(thermal_gap 0.5)
				(thermal_bridge_width 0.5)
				(island_removal_mode 0)
			)
			(polygon
				(pts
					(arc
						(start 297.998388 -6.347206)
						(mid 296.144188 -6.347206)
						(end 297.998388 -6.347206)
					)
				)
			)
		)
		(zone
			(layers "F.Cu" "B.Cu" "In1.Cu" "In2.Cu" "In3.Cu" "In4.Cu" "In5.Cu" "In6.Cu"
				"In7.Cu" "In8.Cu" "In9.Cu" "In10.Cu" "In11.Cu" "In12.Cu" "In13.Cu" "In14.Cu"
				"In15.Cu" "In16.Cu"
			)
			(hatch none 0.5)
			(connect_pads
				(clearance 0)
			)
			(min_thickness 0.25)
			(keepout
				(tracks not_allowed)
				(vias allowed)
				(pads allowed)
				(copperpour not_allowed)
				(footprints allowed)
			)
			(placement
				(enabled no)
				(sheetname "")
			)
			(fill
				(thermal_gap 0.5)
				(thermal_bridge_width 0.5)
				(island_removal_mode 0)
			)
			(polygon
				(pts
					(arc
						(start 297.998388 -3.807206)
						(mid 296.144188 -3.807206)
						(end 297.998388 -3.807206)
					)
				)
			)
		)
		(zone
			(layers "F.Cu" "B.Cu" "In1.Cu" "In2.Cu" "In3.Cu" "In4.Cu" "In5.Cu" "In6.Cu"
				"In7.Cu" "In8.Cu" "In9.Cu" "In10.Cu" "In11.Cu" "In12.Cu" "In13.Cu" "In14.Cu"
				"In15.Cu" "In16.Cu"
			)
			(hatch none 0.5)
			(connect_pads
				(clearance 0)
			)
			(min_thickness 0.25)
			(keepout
				(tracks not_allowed)
				(vias allowed)
				(pads allowed)
				(copperpour not_allowed)
				(footprints allowed)
			)
			(placement
				(enabled no)
				(sheetname "")
			)
			(fill
				(thermal_gap 0.5)
				(thermal_bridge_width 0.5)
				(island_removal_mode 0)
			)
			(polygon
				(pts
					(arc
						(start 304.348388 -6.347206)
						(mid 302.494188 -6.347206)
						(end 304.348388 -6.347206)
					)
				)
			)
		)
		(zone
			(layers "F.Cu" "B.Cu" "In1.Cu" "In2.Cu" "In3.Cu" "In4.Cu" "In5.Cu" "In6.Cu"
				"In7.Cu" "In8.Cu" "In9.Cu" "In10.Cu" "In11.Cu" "In12.Cu" "In13.Cu" "In14.Cu"
				"In15.Cu" "In16.Cu"
			)
			(hatch none 0.5)
			(connect_pads
				(clearance 0)
			)
			(min_thickness 0.25)
			(keepout
				(tracks not_allowed)
				(vias allowed)
				(pads allowed)
				(copperpour not_allowed)
				(footprints allowed)
			)
			(placement
				(enabled no)
				(sheetname "")
			)
			(fill
				(thermal_gap 0.5)
				(thermal_bridge_width 0.5)
				(island_removal_mode 0)
			)
			(polygon
				(pts
					(arc
						(start 304.348388 -3.807206)
						(mid 302.494188 -3.807206)
						(end 304.348388 -3.807206)
					)
				)
			)
		)
	)
)
